# T6G (Grand Teton) — schematic netlist excerpt (pin names and nets, part order shuffled) for the footprints in the layout excerpt that follows; sources: Cadence DE-HDL packaged netlist, KiCad conversion of 04192023_DAF0TMB3IC0_F0TG_MB_C_brd_V02_OCP.brd

R3560  Q_RES  0 5% CHIP  pkg 0402LF  page 237 : A = M2_0_P3V3_ADC_ALERT_R ; B = M2_0_P3V3_ADC_ALERT
C1062  Q_CAP  0.1UF 25V 10% X7R  pkg 0402  page 142 : A = P3V3_AUX ; B = GND

(kicad_pcb
	(version 20260206)
	(generator "pcbnew")
	(generator_version "10.0")
	(general
		(thickness 1.6)
		(legacy_teardrops no)
	)
	(paper "A4")
	(title_block
		(title "04192023_DAF0TMB3IC0_F0TG_MB_C_brd_V02_OCP.brd")
		(comment 1 "Grand Teton / footprints 1420-1421 of 8354")
	)
	(layers
		(0 "F.Cu" signal "TOP")
		(4 "In1.Cu" signal "GND")
		(6 "In2.Cu" signal "IN1")
		(8 "In3.Cu" signal "GND1")
		(10 "In4.Cu" signal "IN2")
		(12 "In5.Cu" signal "GND2")
		(14 "In6.Cu" signal "IN3")
		(16 "In7.Cu" signal "GND3")
		(18 "In8.Cu" signal "VCC")
		(20 "In9.Cu" signal "VCC1")
		(22 "In10.Cu" signal "GND4")
		(24 "In11.Cu" signal "IN4")
		(26 "In12.Cu" signal "GND5")
		(28 "In13.Cu" signal "IN5")
		(30 "In14.Cu" signal "GND6")
		(32 "In15.Cu" signal "IN6")
		(34 "In16.Cu" signal "GND7")
		(2 "B.Cu" signal "BOTTOM")
		(9 "F.Adhes" user "F.Adhesive")
		(11 "B.Adhes" user "B.Adhesive")
		(13 "F.Paste" user "Package Geometry/Pastemask Top")
		(15 "B.Paste" user "Package Geometry/Pastemask Bottom")
		(5 "F.SilkS" user "Ref Des/Silkscreen Top")
		(7 "B.SilkS" user "Ref Des/Silkscreen Bottom")
		(1 "F.Mask" user "Board Geometry/Soldermask Top")
		(3 "B.Mask" user "Board Geometry/Soldermask Bottom")
		(17 "Dwgs.User" user "User.Drawings")
		(19 "Cmts.User" user "User.Comments")
		(21 "Eco1.User" user "User.Eco1")
		(23 "Eco2.User" user "User.Eco2")
		(25 "Edge.Cuts" user "Board Geometry/Outline")
		(27 "Margin" user)
		(31 "F.CrtYd" user "Package Geometry/Place Bound Top")
		(29 "B.CrtYd" user "Package Geometry/Place Bound Bottom")
		(35 "F.Fab" user "Ref Des/Assembly Top")
		(33 "B.Fab" user "Ref Des/Assembly Bottom")
	)
	(footprint ""
		(layer "F.Cu")
		(at 150.502366 -54.172358 180)
		(property "Reference" "R3560"
			(at 0 0 180)
			(layer "F.SilkS")
			(hide yes)
			(effects
				(font
					(size 1.27 1.27)
				)
			)
		)
		(property "Value" ""
			(at 0 0 180)
			(layer "F.Fab")
			(effects
				(font
					(size 1.27 1.27)
				)
			)
		)
		(duplicate_pad_numbers_are_jumpers no)
		(fp_line
			(start 0.7874 0.4064)
			(end -0.7874 0.4064)
			(stroke
				(width 0.1524)
				(type default)
			)
			(layer "F.SilkS")
		)
		(fp_line
			(start 0.7874 -0.4064)
			(end 0.7874 0.4064)
			(stroke
				(width 0.1524)
				(type default)
			)
			(layer "F.SilkS")
		)
		(fp_line
			(start -0.7874 0.4064)
			(end -0.7874 -0.4064)
			(stroke
				(width 0.1524)
				(type default)
			)
			(layer "F.SilkS")
		)
		(fp_line
			(start -0.7874 -0.4064)
			(end 0.7874 -0.4064)
			(stroke
				(width 0.1524)
				(type default)
			)
			(layer "F.SilkS")
		)
		(fp_line
			(start 0.67945 0.3048)
			(end 0.120396 0.3048)
			(stroke
				(width 0.1)
				(type default)
			)
			(layer "F.Fab")
		)
		(fp_line
			(start 0.67945 -0.3048)
			(end 0.67945 0.3048)
			(stroke
				(width 0.1)
				(type default)
			)
			(layer "F.Fab")
		)
		(fp_line
			(start 0.12065 -0.2794)
			(end 0.12065 -0.3048)
			(stroke
				(width 0.1)
				(type default)
			)
			(layer "F.Fab")
		)
		(fp_line
			(start 0.12065 -0.3048)
			(end 0.67945 -0.3048)
			(stroke
				(width 0.1)
				(type default)
			)
			(layer "F.Fab")
		)
		(fp_line
			(start 0.120396 0.3048)
			(end 0.120396 0.2794)
			(stroke
				(width 0.1)
				(type default)
			)
			(layer "F.Fab")
		)
		(fp_line
			(start 0.120396 0.2794)
			(end -0.12065 0.2794)
			(stroke
				(width 0.1)
				(type default)
			)
			(layer "F.Fab")
		)
		(fp_line
			(start -0.12065 0.3048)
			(end -0.67945 0.3048)
			(stroke
				(width 0.1)
				(type default)
			)
			(layer "F.Fab")
		)
		(fp_line
			(start -0.12065 0.2794)
			(end -0.12065 0.3048)
			(stroke
				(width 0.1)
				(type default)
			)
			(layer "F.Fab")
		)
		(fp_line
			(start -0.12065 -0.2794)
			(end 0.12065 -0.2794)
			(stroke
				(width 0.1)
				(type default)
			)
			(layer "F.Fab")
		)
		(fp_line
			(start -0.12065 -0.305054)
			(end -0.12065 -0.2794)
			(stroke
				(width 0.1)
				(type default)
			)
			(layer "F.Fab")
		)
		(fp_line
			(start -0.67945 0.3048)
			(end -0.67945 -0.305054)
			(stroke
				(width 0.1)
				(type default)
			)
			(layer "F.Fab")
		)
		(fp_line
			(start -0.67945 -0.305054)
			(end -0.12065 -0.305054)
			(stroke
				(width 0.1)
				(type default)
			)
			(layer "F.Fab")
		)
		(pad "1" smd circle
			(at -0.40005 0 180)
			(size 0 0)
			(layers "F.Cu" "F.Mask" "F.Paste")
			(net "M2_0_P3V3_ADC_ALERT_R")
		)
		(pad "2" smd circle
			(at 0.40005 0 180)
			(size 0 0)
			(layers "F.Cu" "F.Mask" "F.Paste")
			(net "M2_0_P3V3_ADC_ALERT")
		)
	)
	(footprint ""
		(layer "F.Cu")
		(at 69.977 -59.055 90)
		(property "Reference" "C1062"
			(at 0 0 90)
			(layer "F.SilkS")
			(hide yes)
			(effects
				(font
					(size 1.27 1.27)
				)
			)
		)
		(property "Value" ""
			(at 0 0 90)
			(layer "F.Fab")
			(effects
				(font
					(size 1.27 1.27)
				)
			)
		)
		(duplicate_pad_numbers_are_jumpers no)
		(fp_line
			(start 0.7874 -0.4064)
			(end 0.7874 0.4064)
			(stroke
				(width 0.1524)
				(type default)
			)
			(layer "F.SilkS")
		)
		(fp_line
			(start -0.7874 -0.4064)
			(end 0.7874 -0.4064)
			(stroke
				(width 0.1524)
				(type default)
			)
			(layer "F.SilkS")
		)
		(fp_line
			(start 0.7874 0.4064)
			(end -0.7874 0.4064)
			(stroke
				(width 0.1524)
				(type default)
			)
			(layer "F.SilkS")
		)
		(fp_line
			(start -0.7874 0.4064)
			(end -0.7874 -0.4064)
			(stroke
				(width 0.1524)
				(type default)
			)
			(layer "F.SilkS")
		)
		(fp_line
			(start -0.12065 -0.305054)
			(end -0.12065 -0.2794)
			(stroke
				(width 0.1)
				(type default)
			)
			(layer "F.Fab")
		)
		(fp_line
			(start -0.67945 -0.305054)
			(end -0.12065 -0.305054)
			(stroke
				(width 0.1)
				(type default)
			)
			(layer "F.Fab")
		)
		(fp_line
			(start 0.67945 -0.3048)
			(end 0.67945 0.3048)
			(stroke
				(width 0.1)
				(type default)
			)
			(layer "F.Fab")
		)
		(fp_line
			(start 0.12065 -0.3048)
			(end 0.67945 -0.3048)
			(stroke
				(width 0.1)
				(type default)
			)
			(layer "F.Fab")
		)
		(fp_line
			(start 0.12065 -0.2794)
			(end 0.12065 -0.3048)
			(stroke
				(width 0.1)
				(type default)
			)
			(layer "F.Fab")
		)
		(fp_line
			(start -0.12065 -0.2794)
			(end 0.12065 -0.2794)
			(stroke
				(width 0.1)
				(type default)
			)
			(layer "F.Fab")
		)
		(fp_line
			(start 0.120396 0.2794)
			(end -0.12065 0.2794)
			(stroke
				(width 0.1)
				(type default)
			)
			(layer "F.Fab")
		)
		(fp_line
			(start -0.12065 0.2794)
			(end -0.12065 0.3048)
			(stroke
				(width 0.1)
				(type default)
			)
			(layer "F.Fab")
		)
		(fp_line
			(start 0.67945 0.3048)
			(end 0.120396 0.3048)
			(stroke
				(width 0.1)
				(type default)
			)
			(layer "F.Fab")
		)
		(fp_line
			(start 0.120396 0.3048)
			(end 0.120396 0.2794)
			(stroke
				(width 0.1)
				(type default)
			)
			(layer "F.Fab")
		)
		(fp_line
			(start -0.12065 0.3048)
			(end -0.67945 0.3048)
			(stroke
				(width 0.1)
				(type default)
			)
			(layer "F.Fab")
		)
		(fp_line
			(start -0.67945 0.3048)
			(end -0.67945 -0.305054)
			(stroke
				(width 0.1)
				(type default)
			)
			(layer "F.Fab")
		)
		(pad "1" smd circle
			(at -0.40005 0 90)
			(size 0 0)
			(layers "F.Cu" "F.Mask" "F.Paste")
			(net "P3V3_AUX")
		)
		(pad "2" smd circle
			(at 0.40005 0 90)
			(size 0 0)
			(layers "F.Cu" "F.Mask" "F.Paste")
			(net "GND")
		)
	)
)
